# BASEBOARD_FAB2 (Tioga Pass) — schematic netlist excerpt (pin names and nets, part order shuffled) for the footprints in the layout excerpt that follows; sources: Cadence DE-HDL packaged netlist, KiCad conversion of Wiwynn_Tioga_Pass_MB.brd

U8D7  LCMXO2_A  IC  pkg 256BGA  page 190
  VCC(0)  = P3V3_STBY
  NC(0)  = NC
  PT11C  = FM_PCH_PRSNT_N
  PT10A  = FM_P3V3_CPLD_EN
  PT11A  = TP_CPLD1_PT11A
  PT12D_TDI  = JTAG_PLD_TDI
  PT16C_TCK  = JTAG_PLD_TCK
  PT17B_PCLKC0_1  = TP_CPLD1_PT17B_PCLKC0_1
  PT18C_SCL_PCLKT0_0  = SMB_SENSOR_STBY_LVC3_SCL
  PT19B  = FM_PVCCIN_PVCCSA_CPU0_EN_LVC1
  PT21A  = FM_CPU0_OR_CPU1_MCP_PRES
  PT22B  = PU_THERMTRIP_FORCE_N
  PT24C_INITN  = TP_CPLD1_PT24C_INITN
  PT22D  = TP_CPLD1_PT22D
  PT24B  = TP_CPLD1_PT24B
  VCC(1)  = P3V3_STBY
  PL1C  = RST_PCIE_PCH_PERST_N
  GND(0)  = GND
  PT9C  = FM_CTNR_PS_ON
  PT11D  = PWRGD_PVTT_CPU0
  PT9B  = PWRGD_P12V_MAIN
  PT11B  = TP_CPLD1_PT11B
  PT13A  = TP_CPLD1_PT13A
  PT16D_TMS  = JTAG_PLD_TMS
  PT19A  = PU_RST_PERST_BIT1
  PT20D_PROGRAMN  = PU_CPLD1_PT20D_PROGRAMN
  PT22A  = PWRGD_DSW_PWROK
  PT23B  = FM_PCH_PWRBTN_R1_N
  PT22C  = TP_CPLD1_PT22C
  PT24A  = FM_SINT_PRSNT_N
  GND(1)  = GND
  PR1D  = FM_ADR_COMPLETE_DLY
  PL2C  = RST_PCIE_CPU_DEV1_N
  PL1D  = FM_PCH_PLD_DATA
  GND(2)  = GND
  PT9A  = FM_ADR_SMI_GPIO_R_N
  PT10B  = FM_CPU1_THERMTRIP_LATCH_LVT3_N
  PT12C_TDO  = JTAG_PLD_TDO
  PT13B  = FM_BMC_ONCTL_N
  PT17A_PCLKT0_1  = FM_ADR_COMPLETE
  PT18D_SDA_PCLKC0_0  = SMB_SENSOR_STBY_LVC3_SDA
  PT20C_JTAGENB  = FM_JTAG_PLD_EN_DEBUG
  PT21B  = FM_CPU0_CD_PRES
  PT23A  = FM_SLPS4_N
  PT24D_DONE  = TP_CPLD1_PT24D_DONE
  GND(3)  = GND
  PR1C  = FM_DB1200_PWRGD
  PR2C  = PWRGD_PCH_PWROK
  PL1B_L_GPLLC_FB  = TP_CPLD1_PL1B_L_GPLLC_FB
  PL2D  = FM_MEM_EVENT_FUNC
  PL1A_L_GPLLT_FB  = TP_CPLD1_PL1A_L_GPLLT_FB
  GND(4)  = GND
  VCCIO0(3)  = P3V3_STBY
  PT12A  = RST_PCIE_CPU_DEV0_N
  PT13D  = FM_FORCE_ADR_N
  PT17C  = TP_CPLD1_PT17C
  PT18B  = RST_PCIE_MIDPLANE_N
  PT20A  = TP_CPLD1_PT20A
  PT21D  = FM_CPU0_AND_CPU1_MCP_PRES
  VCCIO0(1)  = P3V3_STBY
  GND(5)  = GND
  PR1A  = PWRGD_SYS_PWROK
  PR2D  = PWRGD_P1V8MCP_CPU0
  PR2A  = PWRGD_P1V8MCP_CPU1
  PL3A_PCLKT5_0  = CLK_32K_SUSCLK_PLD
  PL2A_L_GPLLT_IN  = FM_CPU_CATERR_DLY_LVT3_N
  PL2B_L_GPLLC_IN  = TP_CPLD1_PL2B_L_GPLLC_IN
  VCCIO5(0)  = P3V3_STBY
  GND(6)  = GND
  PT13C  = FM_CPU1_FIVR_FAULT_LVT3_N
  PT12B  = PWRGD_P1V15_BMC_STBY
  PT16B  = TP_CPLD1_PT16B
  PT17D  = FM_SLP_SUS_N
  PT20B  = TP_CPLD1_PT20B
  PT19D  = TP_CPLD1_PT19D
  GND(7)  = GND
  VCCIO1(0)  = P3V3_STBY
  PR2B  = FM_CPLD_ADR_TRIGGER_N
  PR1B  = RST_PLTRST_N
  PR3A  = FM_P1V8MCP_CPU0_EN
  PL4B  = FM_CPU0_PROC_ID0
  PL3B_PCLKC5_0  = FM_CPU0_PKGID0
  PL4A  = FM_CPU0_PROC_ID1
  PL3C  = PU_RST_PERST_BIT0
  PL5C  = FM_CPU0_FIVR_FAULT_LVT3_N
  GND(8)  = GND
  PT16A  = FM_PLD_DEBUG_MODE_N
  PT18A  = SGPIO_BMC_DIN_R
  PT19C  = FM_PS_EN
  PT21C  = FM_CPU1_CD_PRES_N
  GND(9)  = GND
  PR4C  = FM_P1V8MCP_CPU1_EN
  PR3C  = PWRGD_CPUPWRGD
  PR4A  = RST_BMC_SYSRST_BTN_OUT_B_R1_N
  PR3B  = FM_CPU0_MCP_CLK_EN_N
  PR4B  = FM_CPU1_MCP_CLK_EN_N
  PL6A  = FM_SLPS3_N
  PL5A  = FM_CPU0_PKGID2
  PL5B  = FM_CPU0_PKGID1
  PL4D  = RST_RSMRST_R_N
  PL4C  = FM_DEBUG_RST_BTN_N
  PL3D  = FM_PWR_BTN_R2_N
  VCC(4)  = P3V3_STBY
  VCCIO0(0)  = P3V3_STBY
  VCCIO0(2)  = P3V3_STBY
  VCC(5)  = P3V3_STBY
  PR5C  = FM_WBG_PRSNT_N
  PR3D  = FM_CPU0_THERMTRIP_LATCH_LVT3_N
  PR4D  = FM_CPU1_FIVR_FAULT_LVT3
  PR5B  = FM_CPU1_THERMTRIP_LVT3_N
  PR5A  = FM_UV_ADR_TRIGGER_N
  PR6A  = FM_FAST_PROCHOT_THROTTLE_IN_N
  PL7B  = RST_PCIE_CPU_DEV3_N
  PL6B  = FM_PVCCMCP_CPU0_EN
  PL7A  = RST_PCIE_CPU_DEV2_N
  PL6C  = FM_MP_PS_FAIL_N
  PL9C  = NC
  PL5D  = PWRGD_P3V3
  VCCIO4(1)  = P3V3_STBY
  GND(10)  = GND
  GND(11)  = GND
  VCCIO1(1)  = P3V3_STBY
  PR9C  = TP_CPLD1_PR9C
  PR5D  = FM_UV_ADR_TRIGGER_EN
  PR6C  = FM_PVDDQ_GHJ_EN
  PR7A_PCLKT1_0  = TP_CPLD1_PR7A_PCLKT1_0
  PR6B  = FM_PVDDQ_KLM_EN
  PR7B_PCLKC1_0  = TP_CPLD1_PR7B_PCLKC1_0
  PL7C_PCLKT4_0  = SGPIO_BMC_CLK
  PL9A  = SGPIO_BMC_DOUT
  PL7D_PCLKC4_0  = TP_CPLD1_PL7D_PCLKT4_0
  PL9D  = NC
  PL10C  = UART_BMC_RXD5
  PL6D  = PWRGD_P5V
  VCCIO4(0)  = P3V3_STBY
  GND(12)  = GND
  GND(13)  = GND
  VCCIO1(2)  = P3V3_STBY
  PR10C  = TP_CPLD1_PR10C
  PR6D  = FM_FAST_PROCHOT_THROTTLE_DLY_N
  PR9D  = TP_CPLD1_PR9D
  PR7D  = TP_CPLD1_PR7D
  PR9A  = TP_CPLD1_PR9A
  PR7C  = TP_CPLD1_PR7C
  PL9B  = FM_PVCCIOMCP_CPU0_EN
  PL10B  = SP1_BMC_HOST_UART_TX
  PL10A  = SP1_BMC_HOST_UART_RX
  PL11C  = SGPIO_BMC_LD_N
  PL12C  = PWRGD_PVCCIN_CPU0
  PL10D  = UART_BMC_TXD5
  VCC(6)  = P3V3_STBY
  VCCIO2(2)  = P3V3_STBY
  VCCIO2(0)  = P3V3_STBY
  VCC(7)  = P3V3_STBY
  PR12C  = RST_PLTRST_BUF_N
  PR11D  = FM_MEM_THERM_EVENT_PCH_N
  PR11C  = FM_MEM_THERM_EVENT_LVT3_N
  PR10A  = FM_PVDDQ_ABC_EN
  PR10B  = FM_PVDDQ_DEF_EN
  PR9B  = PU_FAB2_MARKER_CPLD
  PL11A  = PWRGD_PVSA_CPU0
  PL12A_PCLKT3_0  = CLK_25M_CPLD
  PL11B  = TP_CPLD1_PL11A
  PL12D  = PWRGD_PVCCMCP_CPU1
  PL11D  = PWRGD_CPU0_LVC3
  GND(14)  = GND
  PB8D  = FM_OC0_USB_N
  PB11D  = PWRGD_PVCCIO_CPU0
  PB12D  = FM_IE_DISABLE_N
  PB18D  = FM_SOL_UART_CH_SEL
  GND(15)  = GND
  PR10D  = PWRGD_P3V3_STBY
  PR12D  = TP_CPLD1_PR12D
  PR11B  = TP_CPLD1_PR11B
  PR12A  = FM_THERMTRIP_DLY
  PR11A  = PWRGD_PVCCIO_CPU1
  PL12B_PCLKC3_0  = RST_RSMRST_DLY
  PL14A  = PWRGD_PVPP_GHJ
  PL13A  = RST_PCIE_RISER1_PERST_N
  VCCIO3(0)  = P3V3_STBY
  GND(16)  = GND
  PB11C  = PWRGD_PVPP_DEF
  PB9C  = FM_PVCCIO_CPU0_EN
  PB16C  = FM_PVCCMCP_CPU1_EN
  PB18C  = FM_CPLD_UART_CH_LOCK_N
  PB21C  = PWRGD_CPU1_LVC3
  PB19D  = XDP_PWRGD_RST_N
  GND(17)  = GND
  VCCIO1(3)  = P3V3_STBY
  PR13A  = FM_CPU1_PROC_ID1
  PR13B  = FM_CPU1_PROC_ID0
  PR12B  = FM_CPU0_FIVR_FAULT_LVT3
  PL13B  = PWRGD_PVCCIN_CPU1
  PL13C  = PWRGD_PVPP_KLM
  PL14B  = RST_CD_CPU0_POR_N
  GND(18)  = GND
  VCCIO2(3)  = P3V3_STBY
  PB8C  = PWRGD_PVCCIOMCP_CPU0
  PB9D  = PWRGD_PVPP_ABC
  PB12C  = FM_156M_CPU1_BRD_OSC_EN
  PB16D  = FM_CPLD_BMC_PWRDN_N
  PB19C  = RST_CPU1_LVC3_R1_N
  PB21D  = XDP_SYSPWROK
  VCCIO2(1)  = P3V3_STBY
  GND(19)  = GND
  PR14B  = FM_CPU1_VRM_OSC_EN
  PR13C  = FM_CPU0_THERMTRIP_LVT3_N
  PR14A  = FM_PVCCIN_PVCCSA_CPU1_EN_LVC1
  PL13D  = FM_GLOBAL_RST_WARN_N
  PL14D  = FM_UART_ALERT_N
  GND(20)  = GND
  PB3A  = FM_CPU1_RC_EN
  PB5B  = PWRGD_PVCCMCP_CPU0
  PB8A_MCLK_CCLK  = TP_CPLD1_PB8A_MCLK_CCLK
  PB9B  = FM_PVCCIOMCP_CPU1_EN
  PB12A  = PWRGD_PVNN_P1V05_PCH
  PB16B_PCLKC2_1  = TP_CPLD1_PB16B_PCLKC2_1
  PB19A  = RST_CD_CPU1_POR_N
  PB21B  = FM_UARTSW_MSB_N
  PB24A  = FM_CPU1_PKGID1
  PB25B_SI_SISPI  = TP_CPLD1_PB25B_SI_SISPI
  GND(21)  = GND
  PR14C  = FM_PVPP_CPU0_EN
  PR13D  = FM_PVPP_CPU1_EN
  PL14C  = FM_BMC_CPLD_GPO
  GND(22)  = GND
  PB3D  = FM_CPU0_RC_EN
  PB6D  = FM_BMC_CPLD_MP_RST_N
  PB5A_CSSPIN  = TP_CPLD1_PB5A_CSSPIN
  PB6B  = RST_PCIE_M2_DEV_N
  PB9A  = PWRGD_PVTT_CPU1
  PB11B_PCLKC2_0  = FM_CPLD_USB_P0_EN_N
  PB18A  = FM_UARTSW_LSB_N
  PB19B  = RST_CPU0_LVC3_R1_N
  PB22A  = FM_DB1200ZL_BCLKS_EN_N
  PB25A_SN  = FM_CPU1_PKGID0
  PB22C  = FM_CPU0_VRM_OSC_EN
  PB25D  = FM_CPU_CATERR_LVT3_N
  GND(23)  = GND
  PR14D  = FM_P12V_MAIN_SW_EN
  VCC(2)  = P3V3_STBY
  PB3C  = FM_ADR_MODE_SEL
  PB6C  = FM_DIS_ADR_DLY
  PB3B  = PWRGD_PVSA_CPU1
  PB6A  = PWRGD_PVCCIOMCP_CPU1
  PB8B_SO_SPISO  = TP_CPLD1_PB8B_SO_SPISO
  PB11A_PCLKT2_0  = FM_PVCCIO_CPU1_EN
  PB12B  = FM_CPLD_DBG_PWR_EN_N
  PB16A_PCLKT2_1  = TP_CPLD1_PB16A_PCLKT2_1
  PB18B  = FM_156M_CPU0_BRD_OSC_EN
  PB21A  = FM_CPU1_PKGID2
  PB22B  = FM_CPU1_SKTOCC_LVT3_N
  PB24B  = FM_CPU_MSMI_LVT3_N
  PB22D  = FM_CPU0_SKTOCC_LVT3_N
  PB25C  = PWRGD_DRAMPWRGD
  VCC(3)  = P3V3_STBY

(kicad_pcb
	(version 20260206)
	(generator "pcbnew")
	(generator_version "10.0")
	(general
		(thickness 1.6)
		(legacy_teardrops no)
	)
	(paper "A4")
	(title_block
		(title "Wiwynn_Tioga_Pass_MB.brd")
		(comment 1 "Tioga Pass / footprint 2035 of 4770 (U8D7), pads 1-44 of 256")
	)
	(layers
		(0 "F.Cu" signal "TOP")
		(4 "In1.Cu" signal "L2GND")
		(6 "In2.Cu" signal "L3")
		(8 "In3.Cu" signal "L4GND")
		(10 "In4.Cu" signal "L5")
		(12 "In5.Cu" signal "L6GND")
		(14 "In6.Cu" signal "L7VCC")
		(16 "In7.Cu" signal "L8VCC")
		(18 "In8.Cu" signal "L9GND")
		(20 "In9.Cu" signal "L10")
		(22 "In10.Cu" signal "L11GND")
		(24 "In11.Cu" signal "L12")
		(26 "In12.Cu" signal "L13GND")
		(2 "B.Cu" signal "BOTTOM")
		(9 "F.Adhes" user "F.Adhesive")
		(11 "B.Adhes" user "B.Adhesive")
		(13 "F.Paste" user "Package Geometry/Pastemask Top")
		(15 "B.Paste" user "Package Geometry/Pastemask Bottom")
		(5 "F.SilkS" user "Ref Des/Silkscreen Top")
		(7 "B.SilkS" user "Ref Des/Silkscreen Bottom")
		(1 "F.Mask" user "Board Geometry/Soldermask Top")
		(3 "B.Mask" user "Board Geometry/Soldermask Bottom")
		(17 "Dwgs.User" user "User.Drawings")
		(19 "Cmts.User" user "User.Comments")
		(21 "Eco1.User" user "User.Eco1")
		(23 "Eco2.User" user "User.Eco2")
		(25 "Edge.Cuts" user "Board Geometry/Outline")
		(27 "Margin" user)
		(31 "F.CrtYd" user "Package Geometry/Place Bound Top")
		(29 "B.CrtYd" user "Package Geometry/Place Bound Bottom")
		(35 "F.Fab" user "Ref Des/Assembly Top")
		(33 "B.Fab" user "Ref Des/Assembly Bottom")
	)
	(footprint ""
		(layer "F.Cu")
		(at 372.745 -74.295 180)
		(property "Reference" "U8D7"
			(at -0.635 -8.28167 0)
			(unlocked yes)
			(layer "F.SilkS")
			(effects
				(font
					(size 0.7874 0.5842)
					(thickness 0.1524)
				)
			)
		)
		(property "Value" ""
			(at 0 0 180)
			(layer "F.Fab")
			(effects
				(font
					(size 1.27 1.27)
				)
			)
		)
		(duplicate_pad_numbers_are_jumpers no)
		(pad "A1" smd circle
			(at -5.999988 -5.999988 180)
			(size 0.3556 0.3556)
			(layers "F.Cu" "F.Mask" "F.Paste")
			(net "P3V3_STBY")
		)
		(pad "A2" smd circle
			(at -5.199888 -5.999988 180)
			(size 0.3556 0.3556)
			(layers "F.Cu" "F.Mask" "F.Paste")
			(net "Net_344")
		)
		(pad "A3" smd circle
			(at -4.400042 -5.999988 180)
			(size 0.3556 0.3556)
			(layers "F.Cu" "F.Mask" "F.Paste")
			(net "FM_PCH_PRSNT_N")
		)
		(pad "A4" smd circle
			(at -3.599942 -5.999988 180)
			(size 0.3556 0.3556)
			(layers "F.Cu" "F.Mask" "F.Paste")
			(net "FM_P3V3_CPLD_EN")
		)
		(pad "A5" smd circle
			(at -2.800096 -5.999988 180)
			(size 0.3556 0.3556)
			(layers "F.Cu" "F.Mask" "F.Paste")
			(net "TP_CPLD1_PT11A")
		)
		(pad "A6" smd circle
			(at -1.999996 -5.999988 180)
			(size 0.3556 0.3556)
			(layers "F.Cu" "F.Mask" "F.Paste")
			(net "JTAG_PLD_TDI")
		)
		(pad "A7" smd circle
			(at -1.199896 -5.999988 180)
			(size 0.3556 0.3556)
			(layers "F.Cu" "F.Mask" "F.Paste")
			(net "JTAG_PLD_TCK")
		)
		(pad "A8" smd circle
			(at -0.40005 -5.999988 180)
			(size 0.3556 0.3556)
			(layers "F.Cu" "F.Mask" "F.Paste")
			(net "TP_CPLD1_PT17B_PCLKC0_1")
		)
		(pad "A9" smd circle
			(at 0.40005 -5.999988 180)
			(size 0.3556 0.3556)
			(layers "F.Cu" "F.Mask" "F.Paste")
			(net "SMB_SENSOR_STBY_LVC3_SCL")
		)
		(pad "A10" smd circle
			(at 1.199896 -5.999988 180)
			(size 0.3556 0.3556)
			(layers "F.Cu" "F.Mask" "F.Paste")
			(net "FM_PVCCIN_PVCCSA_CPU0_EN_LVC1")
		)
		(pad "A11" smd circle
			(at 1.999996 -5.999988 180)
			(size 0.3556 0.3556)
			(layers "F.Cu" "F.Mask" "F.Paste")
			(net "FM_CPU0_OR_CPU1_MCP_PRES")
		)
		(pad "A12" smd circle
			(at 2.800096 -5.999988 180)
			(size 0.3556 0.3556)
			(layers "F.Cu" "F.Mask" "F.Paste")
			(net "PU_THERMTRIP_FORCE_N")
		)
		(pad "A13" smd circle
			(at 3.599942 -5.999988 180)
			(size 0.3556 0.3556)
			(layers "F.Cu" "F.Mask" "F.Paste")
			(net "TP_CPLD1_PT24C_INITN")
		)
		(pad "A14" smd circle
			(at 4.400042 -5.999988 180)
			(size 0.3556 0.3556)
			(layers "F.Cu" "F.Mask" "F.Paste")
			(net "TP_CPLD1_PT22D")
		)
		(pad "A15" smd circle
			(at 5.199888 -5.999988 180)
			(size 0.3556 0.3556)
			(layers "F.Cu" "F.Mask" "F.Paste")
			(net "TP_CPLD1_PT24B")
		)
		(pad "A16" smd circle
			(at 5.999988 -5.999988 180)
			(size 0.3556 0.3556)
			(layers "F.Cu" "F.Mask" "F.Paste")
			(net "P3V3_STBY")
		)
		(pad "B1" smd circle
			(at -5.999988 -5.199888 180)
			(size 0.3556 0.3556)
			(layers "F.Cu" "F.Mask" "F.Paste")
			(net "RST_PCIE_PCH_PERST_N")
		)
		(pad "B2" smd circle
			(at -5.199888 -5.199888 180)
			(size 0.3556 0.3556)
			(layers "F.Cu" "F.Mask" "F.Paste")
			(net "GND")
		)
		(pad "B3" smd circle
			(at -4.400042 -5.199888 180)
			(size 0.3556 0.3556)
			(layers "F.Cu" "F.Mask" "F.Paste")
			(net "FM_CTNR_PS_ON")
		)
		(pad "B4" smd circle
			(at -3.599942 -5.199888 180)
			(size 0.3556 0.3556)
			(layers "F.Cu" "F.Mask" "F.Paste")
			(net "PWRGD_PVTT_CPU0")
		)
		(pad "B5" smd circle
			(at -2.800096 -5.199888 180)
			(size 0.3556 0.3556)
			(layers "F.Cu" "F.Mask" "F.Paste")
			(net "PWRGD_P12V_MAIN")
		)
		(pad "B6" smd circle
			(at -1.999996 -5.199888 180)
			(size 0.3556 0.3556)
			(layers "F.Cu" "F.Mask" "F.Paste")
			(net "TP_CPLD1_PT11B")
		)
		(pad "B7" smd circle
			(at -1.199896 -5.199888 180)
			(size 0.3556 0.3556)
			(layers "F.Cu" "F.Mask" "F.Paste")
			(net "TP_CPLD1_PT13A")
		)
		(pad "B8" smd circle
			(at -0.40005 -5.199888 180)
			(size 0.3556 0.3556)
			(layers "F.Cu" "F.Mask" "F.Paste")
			(net "JTAG_PLD_TMS")
		)
		(pad "B9" smd circle
			(at 0.40005 -5.199888 180)
			(size 0.3556 0.3556)
			(layers "F.Cu" "F.Mask" "F.Paste")
			(net "PU_RST_PERST_BIT1")
		)
		(pad "B10" smd circle
			(at 1.199896 -5.199888 180)
			(size 0.3556 0.3556)
			(layers "F.Cu" "F.Mask" "F.Paste")
			(net "PU_CPLD1_PT20D_PROGRAMN")
		)
		(pad "B11" smd circle
			(at 1.999996 -5.199888 180)
			(size 0.3556 0.3556)
			(layers "F.Cu" "F.Mask" "F.Paste")
			(net "PWRGD_DSW_PWROK")
		)
		(pad "B12" smd circle
			(at 2.800096 -5.199888 180)
			(size 0.3556 0.3556)
			(layers "F.Cu" "F.Mask" "F.Paste")
			(net "FM_PCH_PWRBTN_R1_N")
		)
		(pad "B13" smd circle
			(at 3.599942 -5.199888 180)
			(size 0.3556 0.3556)
			(layers "F.Cu" "F.Mask" "F.Paste")
			(net "TP_CPLD1_PT22C")
		)
		(pad "B14" smd circle
			(at 4.400042 -5.199888 180)
			(size 0.3556 0.3556)
			(layers "F.Cu" "F.Mask" "F.Paste")
			(net "FM_SINT_PRSNT_N")
		)
		(pad "B15" smd circle
			(at 5.199888 -5.199888 180)
			(size 0.3556 0.3556)
			(layers "F.Cu" "F.Mask" "F.Paste")
			(net "GND")
		)
		(pad "B16" smd circle
			(at 5.999988 -5.199888 180)
			(size 0.3556 0.3556)
			(layers "F.Cu" "F.Mask" "F.Paste")
			(net "FM_ADR_COMPLETE_DLY")
		)
		(pad "C1" smd circle
			(at -5.999988 -4.400042 180)
			(size 0.3556 0.3556)
			(layers "F.Cu" "F.Mask" "F.Paste")
			(net "RST_PCIE_CPU_DEV1_N")
		)
		(pad "C2" smd circle
			(at -5.199888 -4.400042 180)
			(size 0.3556 0.3556)
			(layers "F.Cu" "F.Mask" "F.Paste")
			(net "FM_PCH_PLD_DATA")
		)
		(pad "C3" smd circle
			(at -4.400042 -4.400042 180)
			(size 0.3556 0.3556)
			(layers "F.Cu" "F.Mask" "F.Paste")
			(net "GND")
		)
		(pad "C4" smd circle
			(at -3.599942 -4.400042 180)
			(size 0.3556 0.3556)
			(layers "F.Cu" "F.Mask" "F.Paste")
			(net "FM_ADR_SMI_GPIO_R_N")
		)
		(pad "C5" smd circle
			(at -2.800096 -4.400042 180)
			(size 0.3556 0.3556)
			(layers "F.Cu" "F.Mask" "F.Paste")
			(net "FM_CPU1_THERMTRIP_LATCH_LVT3_N")
		)
		(pad "C6" smd circle
			(at -1.999996 -4.400042 180)
			(size 0.3556 0.3556)
			(layers "F.Cu" "F.Mask" "F.Paste")
			(net "JTAG_PLD_TDO")
		)
		(pad "C7" smd circle
			(at -1.199896 -4.400042 180)
			(size 0.3556 0.3556)
			(layers "F.Cu" "F.Mask" "F.Paste")
			(net "FM_BMC_ONCTL_N")
		)
		(pad "C8" smd circle
			(at -0.40005 -4.400042 180)
			(size 0.3556 0.3556)
			(layers "F.Cu" "F.Mask" "F.Paste")
			(net "FM_ADR_COMPLETE")
		)
		(pad "C9" smd circle
			(at 0.40005 -4.400042 180)
			(size 0.3556 0.3556)
			(layers "F.Cu" "F.Mask" "F.Paste")
			(net "SMB_SENSOR_STBY_LVC3_SDA")
		)
		(pad "C10" smd circle
			(at 1.199896 -4.400042 180)
			(size 0.3556 0.3556)
			(layers "F.Cu" "F.Mask" "F.Paste")
			(net "FM_JTAG_PLD_EN_DEBUG")
		)
		(pad "C11" smd circle
			(at 1.999996 -4.400042 180)
			(size 0.3556 0.3556)
			(layers "F.Cu" "F.Mask" "F.Paste")
			(net "FM_CPU0_CD_PRES")
		)
		(pad "C12" smd circle
			(at 2.800096 -4.400042 180)
			(size 0.3556 0.3556)
			(layers "F.Cu" "F.Mask" "F.Paste")
			(net "FM_SLPS4_N")
		)
	)
)
